(kicad_pcb
	(version 20221018)
	(generator pcbnew)
	(general
    (thickness 1.7403)
  )
	(paper "A4")
	(title_block
    (title "Data Center RDIMM DDR4 Tester")
    (date "2024-09-30")
    (rev "1.2.4")
		(comment 9 "footprints 662-670 of 690")
	)
	(layers
    (0 "F.Cu" signal)
    (1 "In1.Cu" power)
    (2 "In2.Cu" signal)
    (3 "In3.Cu" power)
    (4 "In4.Cu" power)
    (5 "In5.Cu" signal)
    (6 "In6.Cu" power)
    (7 "In7.Cu" signal)
    (8 "In8.Cu" power)
    (9 "In9.Cu" signal)
    (10 "In10.Cu" power)
    (31 "B.Cu" signal)
    (32 "B.Adhes" user "B.Adhesive")
    (33 "F.Adhes" user "F.Adhesive")
    (34 "B.Paste" user)
    (35 "F.Paste" user)
    (36 "B.SilkS" user "B.Silkscreen")
    (37 "F.SilkS" user "F.Silkscreen")
    (38 "B.Mask" user)
    (39 "F.Mask" user)
    (40 "Dwgs.User" user "User.Drawings")
    (41 "Cmts.User" user "User.Comments")
    (42 "Eco1.User" user "User.Eco1")
    (43 "Eco2.User" user "User.Eco2")
    (44 "Edge.Cuts" user)
    (45 "Margin" user)
    (46 "B.CrtYd" user "B.Courtyard")
    (47 "F.CrtYd" user "F.Courtyard")
    (48 "B.Fab" user)
    (49 "F.Fab" user)
  )
	(footprint "data-center-rdimm-ddr4-tester-footprints:SC70-3" (layer "B.Cu")
    (at 238.9 77.7)
    (property "Author" "Antmicro")
    (property "License" "Apache-2.0")
    (property "MPN" "BSS138PW")
    (property "Manufacturer" "Nexperia")
    (property "Sheetfile" "interfaces.kicad_sch")
    (property "Sheetname" "Interfaces")
    (property "ki_description" "60 V, 320 mA N-channel enhancement mode Trench MOSFET, SC-70-3 aka SOT-323 package")
    (property "ki_keywords" "n-channel enhancement mosfet sc70 sc-70 sot-323 sot323")
    (attr smd)
    (fp_text reference "Q10" (at -1.35 0.41 180) (layer "B.SilkS")
        (effects (font (size 0.7 0.7) (thickness 0.15)) (justify left bottom mirror))
    )
    (fp_text value "BSS138PW" (at 0 -2.3 180) (layer "B.Fab") hide
        (effects (font (size 0.7 0.7) (thickness 0.15)) (justify left bottom mirror))
    )
    (fp_text user "License: Apache-2.0" (at -1.45 -6.782 180) (layer "B.Fab") hide
        (effects (font (size 0.7 0.7) (thickness 0.15)) (justify left bottom mirror))
    )
    (fp_text user "${REFERENCE}" (at -1.45 -4.783 180) (layer "B.Fab") hide
        (effects (font (size 0.7 0.7) (thickness 0.15)) (justify left bottom mirror))
    )
    (fp_text user "Author: Antmicro" (at -1.45 -5.782 180) (layer "B.Fab") hide
        (effects (font (size 0.7 0.7) (thickness 0.15)) (justify left bottom mirror))
    )
    (fp_line (start -0.3 -1) (end 0.627 -1.001)
      (stroke (width 0.15) (type solid)) (layer "B.SilkS"))
    (fp_line (start -0.3 1) (end 0.627 0.999)
      (stroke (width 0.15) (type solid)) (layer "B.SilkS"))
    (fp_line (start 0.627 -0.6) (end 0.627 -1.001)
      (stroke (width 0.15) (type solid)) (layer "B.SilkS"))
    (fp_line (start 0.627 0.6) (end 0.627 0.999)
      (stroke (width 0.15) (type solid)) (layer "B.SilkS"))
    (fp_rect (start 1.4 -1.3) (end -1.4 1.3)
      (stroke (width 0.05) (type solid)) (fill none) (layer "B.CrtYd"))
    (fp_rect (start -0.623 0.999) (end 0.627 -1.001)
      (stroke (width 0.15) (type solid)) (fill none) (layer "B.Fab"))
    (pad "1" smd rect (at -0.95 0.65 270) (size 0.6 0.8) (layers "B.Cu" "B.Paste" "B.Mask")
      (net 788 "HOT_SWAP_RED") (pinfunction "G") (pintype "bidirectional"))
    (pad "2" smd rect (at -0.95 -0.65 270) (size 0.6 0.8) (layers "B.Cu" "B.Paste" "B.Mask")
      (net 9 "GND") (pinfunction "S") (pintype "bidirectional"))
    (pad "3" smd rect (at 0.95 0 270) (size 0.6 0.8) (layers "B.Cu" "B.Paste" "B.Mask")
      (net 582 "Net-(Q10-D)") (pinfunction "D") (pintype "bidirectional"))
  )
	(footprint "data-center-rdimm-ddr4-tester-footprints:C_0201" (layer "B.Cu")
    (at 187.34 103.1)
    (descr "Capacitor SMD 0201")
    (tags "capacitor SMD 0201")
    (property "Author" "Antmicro")
    (property "Dielectric" "")
    (property "License" "Apache-2.0")
    (property "MPN" "CC0201KRX6S5BB104")
    (property "Manufacturer" "Yaego")
    (property "Sheetfile" "fpga-power.kicad_sch")
    (property "Sheetname" "FPGA power")
    (property "Val" "100n")
    (property "Voltage" "")
    (property "ki_description" " ")
    (attr smd)
    (fp_text reference "C305" (at 0.98 1.11 180) (layer "B.SilkS")
        (effects (font (size 0.7 0.7) (thickness 0.15)) (justify left bottom mirror))
    )
    (fp_text value "C_100n_0201" (at 0 -1.4 180) (layer "B.Fab") hide
        (effects (font (size 0.7 0.7) (thickness 0.15)) (justify left bottom mirror))
    )
    (fp_text user "${REFERENCE}" (at -0.72 -3.4 180) (layer "B.Fab") hide
        (effects (font (size 0.7 0.7) (thickness 0.15)) (justify left bottom mirror))
    )
    (fp_text user "License: Apache-2.0" (at -0.72 -4.4 180) (layer "B.Fab") hide
        (effects (font (size 0.7 0.7) (thickness 0.15)) (justify left bottom mirror))
    )
    (fp_text user "Author: Antmicro" (at -0.72 -5.4 180) (layer "B.Fab") hide
        (effects (font (size 0.7 0.7) (thickness 0.15)) (justify left bottom mirror))
    )
    (fp_rect (start -0.72 0.38) (end 0.72 -0.38)
      (stroke (width 0.05) (type solid)) (fill none) (layer "B.CrtYd"))
    (fp_rect (start 0.3 -0.15) (end -0.301 0.149)
      (stroke (width 0.15) (type solid)) (fill none) (layer "B.Fab"))
    (pad "" smd roundrect (at -0.349 0.002) (size 0.318 0.36) (layers "B.Paste") (roundrect_rratio 0.25))
    (pad "" smd roundrect (at 0.341 0.002) (size 0.318 0.36) (layers "B.Paste") (roundrect_rratio 0.25))
    (pad "1" smd roundrect (at -0.321 0.002) (size 0.46 0.4) (layers "B.Cu" "B.Mask") (roundrect_rratio 0.25)
      (net 143 "3V3_SYS") (pintype "passive"))
    (pad "2" smd roundrect (at 0.32 0.002) (size 0.46 0.4) (layers "B.Cu" "B.Mask") (roundrect_rratio 0.25)
      (net 9 "GND") (pintype "passive"))
  )
	(footprint "data-center-rdimm-ddr4-tester-footprints:C_0402_1005Metric" (layer "B.Cu")
    (at 163.1 122.25 180)
    (descr "Capacitor SMD 0402")
    (tags "capacitor SMD 0402")
    (property "Author" "Antmicro")
    (property "Dielectric" "")
    (property "License" "Apache-2.0")
    (property "MPN" "MC0402B104K160CT")
    (property "Manufacturer" "Multicomp")
    (property "Sheetfile" "ethernet.kicad_sch")
    (property "Sheetname" "Ethernet")
    (property "Val" "100n")
    (property "Voltage" "")
    (property "ki_description" " ")
    (attr smd)
    (fp_text reference "C221" (at -1.45 -1.28) (layer "B.SilkS")
        (effects (font (size 0.7 0.7) (thickness 0.15)) (justify left bottom mirror))
    )
    (fp_text value "C_100n_16V_0402" (at 0 -1.4) (layer "B.Fab") hide
        (effects (font (size 0.7 0.7) (thickness 0.15)) (justify left bottom mirror))
    )
    (fp_text user "${REFERENCE}" (at -0.932 -3.168) (layer "B.Fab") hide
        (effects (font (size 0.7 0.7) (thickness 0.15)) (justify left bottom mirror))
    )
    (fp_text user "License: Apache-2.0" (at -0.932 -5.17) (layer "B.Fab") hide
        (effects (font (size 0.7 0.7) (thickness 0.15)) (justify left bottom mirror))
    )
    (fp_text user "Author: Antmicro" (at -0.932 -4.17) (layer "B.Fab") hide
        (effects (font (size 0.7 0.7) (thickness 0.15)) (justify left bottom mirror))
    )
    (fp_rect (start -0.94 0.47) (end 0.94 -0.47)
      (stroke (width 0.05) (type solid)) (fill none) (layer "B.CrtYd"))
    (fp_rect (start -0.499 0.249) (end 0.499 -0.249)
      (stroke (width 0.15) (type solid)) (fill none) (layer "B.Fab"))
    (pad "1" smd roundrect (at -0.484 0 180) (size 0.59 0.64) (layers "B.Cu" "B.Paste" "B.Mask") (roundrect_rratio 0.25)
      (net 92 "Net-(J2-P4)") (pintype "passive"))
    (pad "2" smd roundrect (at 0.484 0 180) (size 0.59 0.64) (layers "B.Cu" "B.Paste" "B.Mask") (roundrect_rratio 0.25)
      (net 9 "GND") (pintype "passive"))
  )
	(footprint "data-center-rdimm-ddr4-tester-footprints:C_0201" (layer "B.Cu")
    (at 196.14 92.53 90)
    (descr "Capacitor SMD 0201")
    (tags "capacitor SMD 0201")
    (property "Author" "Antmicro")
    (property "Dielectric" "")
    (property "License" "Apache-2.0")
    (property "MPN" "CC0201KRX6S5BB104")
    (property "Manufacturer" "Yaego")
    (property "Sheetfile" "fpga-power.kicad_sch")
    (property "Sheetname" "FPGA power")
    (property "Val" "100n")
    (property "Voltage" "")
    (property "ki_description" " ")
    (attr smd)
    (fp_text reference "C253" (at 0.85 2.65 270) (layer "B.SilkS")
        (effects (font (size 0.7 0.7) (thickness 0.15)) (justify left bottom mirror))
    )
    (fp_text value "C_100n_0201" (at 0 -1.4 270) (layer "B.Fab") hide
        (effects (font (size 0.7 0.7) (thickness 0.15)) (justify left bottom mirror))
    )
    (fp_text user "Author: Antmicro" (at -0.72 -5.4 270) (layer "B.Fab") hide
        (effects (font (size 0.7 0.7) (thickness 0.15)) (justify left bottom mirror))
    )
    (fp_text user "${REFERENCE}" (at -0.72 -3.4 270) (layer "B.Fab") hide
        (effects (font (size 0.7 0.7) (thickness 0.15)) (justify left bottom mirror))
    )
    (fp_text user "License: Apache-2.0" (at -0.72 -4.4 270) (layer "B.Fab") hide
        (effects (font (size 0.7 0.7) (thickness 0.15)) (justify left bottom mirror))
    )
    (fp_rect (start -0.72 0.38) (end 0.72 -0.38)
      (stroke (width 0.05) (type solid)) (fill none) (layer "B.CrtYd"))
    (fp_rect (start 0.3 -0.15) (end -0.301 0.149)
      (stroke (width 0.15) (type solid)) (fill none) (layer "B.Fab"))
    (pad "" smd roundrect (at -0.349 0.002 90) (size 0.318 0.36) (layers "B.Paste") (roundrect_rratio 0.25))
    (pad "" smd roundrect (at 0.341 0.002 90) (size 0.318 0.36) (layers "B.Paste") (roundrect_rratio 0.25))
    (pad "1" smd roundrect (at -0.321 0.002 90) (size 0.46 0.4) (layers "B.Cu" "B.Mask") (roundrect_rratio 0.25)
      (net 306 "1V2_SYS") (pintype "passive"))
    (pad "2" smd roundrect (at 0.32 0.002 90) (size 0.46 0.4) (layers "B.Cu" "B.Mask") (roundrect_rratio 0.25)
      (net 9 "GND") (pintype "passive"))
  )
	(footprint "data-center-rdimm-ddr4-tester-footprints:TP_SMD_0.75mm" (layer "B.Cu")
    (at 243.5 127 180)
    (property "Author" "Antmicro")
    (property "License" "Apache-2.0")
    (property "MPN" "")
    (property "Manufacturer" "")
    (property "Sheetfile" "fmc_hpc.kicad_sch")
    (property "Sheetname" "FMC HPC")
    (property "ki_description" "Test Point 0.75mm")
    (attr exclude_from_pos_files)
    (fp_text reference "TP15" (at -0.45 -0.38 90) (layer "B.SilkS")
        (effects (font (size 0.7 0.7) (thickness 0.15)) (justify left bottom mirror))
    )
    (fp_text value "TP_0.75mm_SMD" (at 0 -1.2) (layer "B.Fab") hide
        (effects (font (size 0.7 0.7) (thickness 0.15)) (justify left bottom mirror))
    )
    (fp_text user "${REFERENCE}" (at -0.4 -2.7) (layer "B.Fab") hide
        (effects (font (size 0.7 0.7) (thickness 0.15)) (justify left bottom mirror))
    )
    (fp_text user "License: Apache-2.0" (at -0.4 -5.101) (layer "B.Fab") hide
        (effects (font (size 0.7 0.7) (thickness 0.15)) (justify left bottom mirror))
    )
    (fp_text user "Author: Antmicro" (at -0.4 -3.901) (layer "B.Fab") hide
        (effects (font (size 0.7 0.7) (thickness 0.15)) (justify left bottom mirror))
    )
    (pad "1" smd circle (at 0 0 180) (size 0.75 0.75) (layers "B.Cu" "B.Mask")
      (net 542 "Net-(J5A-VREF_{B_M2C})") (pinfunction "1") (pintype "passive"))
  )
	(footprint "data-center-rdimm-ddr4-tester-footprints:R_0402_1005Metric" (layer "B.Cu")
    (at 241.1 120.1 180)
    (descr "Resistor SMD 0402")
    (tags "resistor SMD 0402")
    (property "Author" "Antmicro")
    (property "License" "Apache-2.0")
    (property "MPN" "CR0402-FX-1002GLF")
    (property "Manufacturer" "Bourns")
    (property "Sheetfile" "fmc_hpc.kicad_sch")
    (property "Sheetname" "FMC HPC")
    (property "Tolerance" "1%")
    (property "Val" "10k")
    (property "ki_description" "10k resistor in 0402 package with 1% tolerance")
    (attr smd)
    (fp_text reference "R208" (at 0.87 -0.37) (layer "B.SilkS")
        (effects (font (size 0.7 0.7) (thickness 0.15)) (justify left bottom mirror))
    )
    (fp_text value "R_10k_0402" (at 0 -1.4) (layer "B.Fab") hide
        (effects (font (size 0.7 0.7) (thickness 0.15)) (justify left bottom mirror))
    )
    (fp_text user "${REFERENCE}" (at -0.95 -3.168) (layer "B.Fab") hide
        (effects (font (size 0.7 0.7) (thickness 0.15)) (justify left bottom mirror))
    )
    (fp_text user "License: Apache-2.0" (at -0.95 -5.169) (layer "B.Fab") hide
        (effects (font (size 0.7 0.7) (thickness 0.15)) (justify left bottom mirror))
    )
    (fp_text user "Author: Antmicro" (at -0.95 -4.169) (layer "B.Fab") hide
        (effects (font (size 0.7 0.7) (thickness 0.15)) (justify left bottom mirror))
    )
    (fp_rect (start -0.93 0.47) (end 0.93 -0.47)
      (stroke (width 0.05) (type solid)) (fill none) (layer "B.CrtYd"))
    (fp_rect (start -0.5 0.25) (end 0.5 -0.25)
      (stroke (width 0.15) (type solid)) (fill none) (layer "B.Fab"))
    (pad "1" smd roundrect (at -0.485 0 180) (size 0.59 0.64) (layers "B.Cu" "B.Paste" "B.Mask") (roundrect_rratio 0.25)
      (net 751 "PRSNT_M2C") (pintype "passive"))
    (pad "2" smd roundrect (at 0.485 0 180) (size 0.59 0.64) (layers "B.Cu" "B.Paste" "B.Mask") (roundrect_rratio 0.25)
      (net 143 "3V3_SYS") (pintype "passive"))
  )
	(footprint "data-center-rdimm-ddr4-tester-footprints:R_0603_1608Metric" (layer "B.Cu")
    (at 153.15 123.55)
    (descr "Resistor SMD 0603")
    (tags "resistor SMD 0603")
    (property "Author" "Antmicro")
    (property "License" "Apache-2.0")
    (property "MPN" "ERJ-UP3F3300V")
    (property "Manufacturer" "Panasonic")
    (property "Sheetfile" "supply.kicad_sch")
    (property "Sheetname" "Supply")
    (property "Tolerance" "1%")
    (property "Val" "330R")
    (property "ki_description" "330R resistor in 0603 package with 1% tolerance")
    (attr smd)
    (fp_text reference "R113" (at 1.48 1.32 180) (layer "B.SilkS")
        (effects (font (size 0.7 0.7) (thickness 0.15)) (justify left bottom mirror))
    )
    (fp_text value "R_330R_0.25W_0603" (at 0 -1.6 180) (layer "B.Fab") hide
        (effects (font (size 0.7 0.7) (thickness 0.15)) (justify left bottom mirror))
    )
    (fp_text user "License: Apache-2.0" (at -1.25 -5.9 180) (layer "B.Fab") hide
        (effects (font (size 0.7 0.7) (thickness 0.15)) (justify left bottom mirror))
    )
    (fp_text user "Author: Antmicro" (at -1.25 -4.9 180) (layer "B.Fab") hide
        (effects (font (size 0.7 0.7) (thickness 0.15)) (justify left bottom mirror))
    )
    (fp_text user "${REFERENCE}" (at -1.25 -3.898 180) (layer "B.Fab") hide
        (effects (font (size 0.7 0.7) (thickness 0.15)) (justify left bottom mirror))
    )
    (fp_line (start -0.3 -0.3) (end 0.3 -0.3)
      (stroke (width 0.15) (type solid)) (layer "B.SilkS"))
    (fp_line (start -0.3 0.3) (end 0.3 0.3)
      (stroke (width 0.15) (type solid)) (layer "B.SilkS"))
    (fp_rect (start -1.25 0.7) (end 1.25 -0.7)
      (stroke (width 0.05) (type solid)) (fill none) (layer "B.CrtYd"))
    (fp_rect (start -0.8 0.4) (end 0.8 -0.4)
      (stroke (width 0.15) (type solid)) (fill none) (layer "B.Fab"))
    (pad "1" smd roundrect (at -0.7 0) (size 0.6 0.8) (layers "B.Cu" "B.Paste" "B.Mask") (roundrect_rratio 0.2)
      (net 856 "Net-(R113-Pad1)") (pintype "passive"))
    (pad "2" smd roundrect (at 0.7 0) (size 0.6 0.8) (layers "B.Cu" "B.Paste" "B.Mask") (roundrect_rratio 0.2)
      (net 306 "1V2_SYS") (pintype "passive"))
  )
	(footprint "data-center-rdimm-ddr4-tester-footprints:SC-74-6_1.5x2.9mm_P0.95mm" (layer "B.Cu")
    (at 121.9 120.1 90)
    (descr "https://assets.nexperia.com/documents/data-sheet/IP4220CZ6.pdf")
    (tags "sc74 sc-74 sot23-6 sot457 tsop6 tsop-6")
    (property "Author" "Antmicro")
    (property "License" "Apache-2.0")
    (property "MPN" "74LVC2G07GV,125")
    (property "Manufacturer" "Nexperia")
    (property "Sheetfile" "supply.kicad_sch")
    (property "Sheetname" "Supply")
    (property "ki_description" "Dual Buffer w/ Open Drain, Low-Voltage CMOS, TSOP6 (SOT457/SC-74/SOT23-6) package 1.1mm height, Texas Instruments Equivalent: SN74LVC2G07DBVR")
    (property "ki_keywords" "Dual Gate Buffer Open Drain LVC CMOS")
    (attr smd)
    (fp_text reference "U24" (at -1.67 -1.28) (layer "B.SilkS")
        (effects (font (size 0.7 0.7) (thickness 0.15)) (justify left bottom mirror))
    )
    (fp_text value "74LVC2G07_SOT457" (at -2 -2.999 270) (layer "B.Fab") hide
        (effects (font (size 0.7 0.7) (thickness 0.15)) (justify left bottom mirror))
    )
    (fp_text user "Author: Antmicro" (at -2.12 -4.999 270) (layer "B.Fab") hide
        (effects (font (size 0.7 0.7) (thickness 0.15)) (justify left bottom mirror))
    )
    (fp_text user "License: Apache-2.0" (at -2.12 -6.199 270) (layer "B.Fab") hide
        (effects (font (size 0.7 0.7) (thickness 0.15)) (justify left bottom mirror))
    )
    (fp_text user "${REFERENCE}" (at -2.12 -7.399 270) (layer "B.Fab") hide
        (effects (font (size 0.7 0.7) (thickness 0.15)) (justify left bottom mirror))
    )
    (fp_circle (center -2.07 0.956) (end -2.02 0.956)
      (stroke (width 0.15) (type solid)) (fill solid) (layer "B.SilkS"))
    (fp_circle (center -2.069 0.956) (end -2.02 0.956)
      (stroke (width 0.15) (type solid)) (fill solid) (layer "B.SilkS"))
    (fp_rect (start -1.714 1.897) (end 1.711 -1.896)
      (stroke (width 0.05) (type solid)) (fill none) (layer "B.CrtYd"))
    (fp_line (start -1.27 -1.372) (end -1.168 -1.372)
      (stroke (width 0.15) (type solid)) (layer "B.Fab"))
    (fp_line (start -1.27 0.915) (end -1.27 -1.372)
      (stroke (width 0.15) (type solid)) (layer "B.Fab"))
    (fp_line (start -1.168 -1.372) (end 1.219 -1.372)
      (stroke (width 0.15) (type solid)) (layer "B.Fab"))
    (fp_line (start -0.761 1.422) (end -1.27 0.915)
      (stroke (width 0.15) (type solid)) (layer "B.Fab"))
    (fp_line (start 1.219 -1.372) (end 1.219 1.422)
      (stroke (width 0.15) (type solid)) (layer "B.Fab"))
    (fp_line (start 1.219 1.422) (end -0.761 1.422)
      (stroke (width 0.15) (type solid)) (layer "B.Fab"))
    (fp_circle (center -2.069 0.956) (end -2.02 0.956)
      (stroke (width 0.15) (type solid)) (fill solid) (layer "B.Fab"))
    (pad "1" smd roundrect (at -1.214 0.955 90) (size 0.8 0.55) (layers "B.Cu" "B.Paste" "B.Mask") (roundrect_rratio 0.15)
      (net 153 "/Supply/VCC_IO_EN") (pintype "input"))
    (pad "2" smd roundrect (at -1.214 0.003 90) (size 0.8 0.55) (layers "B.Cu" "B.Paste" "B.Mask") (roundrect_rratio 0.15)
      (net 9 "GND") (pinfunction "GND") (pintype "power_in"))
    (pad "3" smd roundrect (at -1.214 -0.947 90) (size 0.8 0.55) (layers "B.Cu" "B.Paste" "B.Mask") (roundrect_rratio 0.15)
      (net 153 "/Supply/VCC_IO_EN") (pintype "input"))
    (pad "4" smd roundrect (at 1.187 -0.947 90) (size 0.8 0.55) (layers "B.Cu" "B.Paste" "B.Mask") (roundrect_rratio 0.15)
      (net 857 "Net-(R114-Pad1)") (pintype "output"))
    (pad "5" smd roundrect (at 1.187 0.003 90) (size 0.8 0.55) (layers "B.Cu" "B.Paste" "B.Mask") (roundrect_rratio 0.15)
      (net 307 "5V0_SYS") (pinfunction "V_{CC}") (pintype "power_in"))
    (pad "6" smd roundrect (at 1.187 0.955 90) (size 0.8 0.55) (layers "B.Cu" "B.Paste" "B.Mask") (roundrect_rratio 0.15)
      (net 856 "Net-(R113-Pad1)") (pintype "output"))
  )
	(footprint "data-center-rdimm-ddr4-tester-footprints:R_0402_1005Metric" (layer "B.Cu")
    (at 136.47 102.12 180)
    (descr "Resistor SMD 0402")
    (tags "resistor SMD 0402")
    (property "Author" "Antmicro")
    (property "Current" "1A")
    (property "DNP" "DNP")
    (property "License" "Apache-2.0")
    (property "MPN" "ERJ2GE0R00X")
    (property "Manufacturer" "Panasonic")
    (property "Sheetfile" "supply.kicad_sch")
    (property "Sheetname" "Supply")
    (property "Tolerance" "")
    (property "Val" "0R")
    (property "dnp" "")
    (property "exclude_from_bom" "")
    (property "ki_description" "0R resistor in 0402 package with unspecified tolerance")
    (attr exclude_from_pos_files exclude_from_bom)
    (fp_text reference "R196" (at -1.81 -1.32) (layer "B.SilkS")
        (effects (font (size 0.7 0.7) (thickness 0.15)) (justify left bottom mirror))
    )
    (fp_text value "R_0R_0402" (at 0 -1.4) (layer "B.Fab") hide
        (effects (font (size 0.7 0.7) (thickness 0.15)) (justify left bottom mirror))
    )
    (fp_text user "Author: Antmicro" (at -0.95 -4.169) (layer "B.Fab") hide
        (effects (font (size 0.7 0.7) (thickness 0.15)) (justify left bottom mirror))
    )
    (fp_text user "${REFERENCE}" (at -0.95 -3.168) (layer "B.Fab") hide
        (effects (font (size 0.7 0.7) (thickness 0.15)) (justify left bottom mirror))
    )
    (fp_text user "License: Apache-2.0" (at -0.95 -5.169) (layer "B.Fab") hide
        (effects (font (size 0.7 0.7) (thickness 0.15)) (justify left bottom mirror))
    )
    (fp_rect (start -0.93 0.47) (end 0.93 -0.47)
      (stroke (width 0.05) (type solid)) (fill none) (layer "B.CrtYd"))
    (fp_rect (start -0.5 0.25) (end 0.5 -0.25)
      (stroke (width 0.15) (type solid)) (fill none) (layer "B.Fab"))
    (pad "1" smd roundrect (at -0.485 0 180) (size 0.59 0.64) (layers "B.Cu" "B.Paste" "B.Mask") (roundrect_rratio 0.25)
      (net 153 "/Supply/VCC_IO_EN") (pintype "passive"))
    (pad "2" smd roundrect (at 0.485 0 180) (size 0.59 0.64) (layers "B.Cu" "B.Paste" "B.Mask") (roundrect_rratio 0.25)
      (net 793 "/Supply/VTT_CNTL") (pintype "passive"))
  )
)
